# S9S_MB_2U (Grand Teton) — schematic netlist excerpt (pin names and nets, part order shuffled) for the footprints in the layout excerpt that follows; sources: Cadence DE-HDL packaged netlist, KiCad conversion of 03242023_DA0F0TMBIJ0_F0T_Motherboard_J_brd_V01_OCP.brd

J27  SCONN288_ADR50017P130CC  SCONN288_ADR50017-P130CC IO  pkg DDR288S_1-1VXB  page 108
  VIN_BULK0  = P12V_S3_AUX_CPU1_NVDIMM
  RFU0  = TP_CHF_CPU1_DIMM1_FRU_0
  VIN_MGMT  = P3V3_AUX
  HSCL  = I3C_SPD_DDREFGH_CPU1_LVC1_SCL_2
  HSDA  = I3C_SPD_DDREFGH_CPU1_LVC1_SDA
  VSS0  = GND
  DQ0_A  = M_F_CPU1_SA_DQ<0>
  VSS1  = GND
  DQ1_A  = M_F_CPU1_SA_DQ<1>
  VSS2  = GND
  DQS0_A_T  = M_F_CPU1_SA_DQS_DP<0>
  DQS0_A_C  = M_F_CPU1_SA_DQS_DN<0>
  VSS3  = GND
  DQ4_A  = M_F_CPU1_SA_DQ<4>
  VSS4  = GND
  DQ5_A  = M_F_CPU1_SA_DQ<5>
  VSS5  = GND
  DQ8_A  = M_F_CPU1_SA_DQ<8>
  VSS6  = GND
  DQ9_A  = M_F_CPU1_SA_DQ<9>
  VSS7  = GND
  DQS1_A_T  = M_F_CPU1_SA_DQS_DP<1>
  DQS1_A_C  = M_F_CPU1_SA_DQS_DN<1>
  VSS8  = GND
  DQ12_A  = M_F_CPU1_SA_DQ<12>
  VSS9  = GND
  DQ13_A  = M_F_CPU1_SA_DQ<13>
  VSS10  = GND
  DQ16_A  = M_F_CPU1_SA_DQ<16>
  VSS11  = GND
  DQ17_A  = M_F_CPU1_SA_DQ<17>
  VSS12  = GND
  DQS2_A_T  = M_F_CPU1_SA_DQS_DP<2>
  DQS2_A_C  = M_F_CPU1_SA_DQS_DN<2>
  VSS13  = GND
  DQ20_A  = M_F_CPU1_SA_DQ<20>
  VSS14  = GND
  DQ21_A  = M_F_CPU1_SA_DQ<21>
  VSS15  = GND
  DQ24_A  = M_F_CPU1_SA_DQ<24>
  VSS16  = GND
  DQ25_A  = M_F_CPU1_SA_DQ<25>
  VSS17  = GND
  DQS3_A_T  = M_F_CPU1_SA_DQS_DP<3>
  DQS3_A_C  = M_F_CPU1_SA_DQS_DN<3>
  VSS18  = GND
  DQ28_A  = M_F_CPU1_SA_DQ<28>
  VSS19  = GND
  DQ29_A  = M_F_CPU1_SA_DQ<29>
  VSS20  = GND
  CB0_A  = M_F_CPU1_SA_CB<0>
  VSS21  = GND
  CB1_A  = M_F_CPU1_SA_CB<1>
  VSS22  = GND
  DQS4_A_T  = M_F_CPU1_SA_DQS_DP<4>
  DQS4_A_C  = M_F_CPU1_SA_DQS_DN<4>
  VSS23  = GND
  CB4_A  = M_F_CPU1_SA_CB<4>
  VSS24  = GND
  CB5_A  = M_F_CPU1_SA_CB<5>
  VSS25  = GND
  ALERT_N  = M_F_CPU1_ALERT_N
  VSS26  = GND
  CS0_A_N  = M_F_CPU1_SA_CS_N<0>
  VSS27  = GND
  CA0_A  = M_F_CPU1_SA_CA<0>
  VSS28  = GND
  CA2_A  = M_F_CPU1_SA_CA<2>
  VSS29  = GND
  CA4_A  = M_F_CPU1_SA_CA<4>
  VSS30  = GND
  CA6_A  = M_F_CPU1_SA_CA<6>
  VSS31  = GND
  PAR_A  = M_F_CPU1_SA_PAR
  VSS32  = GND
  CA0_B  = M_F_CPU1_SB_CA<0>
  VSS33  = GND
  CA2_B  = M_F_CPU1_SB_CA<2>
  VSS34  = GND
  CA4_B  = M_F_CPU1_SB_CA<4>
  VSS35  = GND
  CA6_B  = M_F_CPU1_SB_CA<6>
  VSS36  = GND
  CS0_B_N  = M_F_CPU1_SB_CS_N<0>
  VSS37  = GND
  \lbd||rsp_a_n\  = M_F_CPU1_SA_RSP<0>
  \lbs||rsp_b_n\  = M_F_CPU1_SB_RSP<0>
  VSS38  = GND
  CB4_B  = M_F_CPU1_SB_CB<4>
  VSS39  = GND
  CB5_B  = M_F_CPU1_SB_CB<5>
  VSS40  = GND
  \dqs9_b_t||tdqs9_b_t||dbi4_b_n\  = M_F_CPU1_SB_DQS_DP<9>
  \dqs9_b_c||tdqs9_b_c\  = M_F_CPU1_SB_DQS_DN<9>
  VSS41  = GND
  CB0_B  = M_F_CPU1_SB_CB<0>
  VSS42  = GND
  CB1_B  = M_F_CPU1_SB_CB<1>
  VSS43  = GND
  DQ0_B  = M_F_CPU1_SB_DQ<0>
  VSS44  = GND
  DQ1_B  = M_F_CPU1_SB_DQ<1>
  VSS45  = GND
  DQS0_B_T  = M_F_CPU1_SB_DQS_DP<0>
  DQS0_B_C  = M_F_CPU1_SB_DQS_DN<0>
  VSS46  = GND
  DQ4_B  = M_F_CPU1_SB_DQ<4>
  VSS47  = GND
  DQ5_B  = M_F_CPU1_SB_DQ<5>
  VSS48  = GND
  DQ8_B  = M_F_CPU1_SB_DQ<8>
  VSS49  = GND
  DQ9_B  = M_F_CPU1_SB_DQ<9>
  VSS50  = GND
  DQS1_B_T  = M_F_CPU1_SB_DQS_DP<1>
  DQS1_B_C  = M_F_CPU1_SB_DQS_DN<1>
  VSS51  = GND
  DQ12_B  = M_F_CPU1_SB_DQ<12>
  VSS52  = GND
  DQ13_B  = M_F_CPU1_SB_DQ<13>
  VSS53  = GND
  DQ16_B  = M_F_CPU1_SB_DQ<16>
  VSS54  = GND
  DQ17_B  = M_F_CPU1_SB_DQ<17>
  VSS55  = GND
  DQS2_B_T  = M_F_CPU1_SB_DQS_DP<2>
  DQS2_B_C  = M_F_CPU1_SB_DQS_DN<2>
  VSS56  = GND
  DQ20_B  = M_F_CPU1_SB_DQ<20>
  VSS57  = GND
  DQ21_B  = M_F_CPU1_SB_DQ<21>
  VSS58  = GND
  DQ24_B  = M_F_CPU1_SB_DQ<24>
  VSS59  = GND
  DQ25_B  = M_F_CPU1_SB_DQ<25>
  VSS60  = GND
  DQS3_B_T  = M_F_CPU1_SB_DQS_DP<3>
  DQS3_B_C  = M_F_CPU1_SB_DQS_DN<3>
  VSS61  = GND
  DQ28_B  = M_F_CPU1_SB_DQ<28>
  VSS62  = GND
  DQ29_B  = M_F_CPU1_SB_DQ<29>
  VSS63  = GND
  RFU1  = TP_CHF_CPU1_DIMM1_FRU_1
  VIN_BULK1  = P12V_S3_AUX_CPU1_NVDIMM
  VIN_BULK2  = P12V_S3_AUX_CPU1_NVDIMM
  \pwr_good||fail_n\  = PWRGD_CHF_CPU1_DIMM1
  HSA  = PD_CHF_CPU1_DIMM1_SAA
  RFU2  = TP_CHF_CPU1_DIMM1_FRU_2
  RFU3  = TP_CHF_CPU1_DIMM1_FRU_3
  VSS64  = GND
  DQ2_A  = M_F_CPU1_SA_DQ<2>
  VSS65  = GND
  DQ3_A  = M_F_CPU1_SA_DQ<3>
  VSS66  = GND
  \dqs5_a_c||tdqs5_a_c||dqs5_a_t||tdqs5_a_t\  = M_F_CPU1_SA_DQS_DN<5>
  \dqs5_a_t||tdqs5_a_t\  = M_F_CPU1_SA_DQS_DP<5>
  VSS67  = GND
  DQ6_A  = M_F_CPU1_SA_DQ<6>
  VSS68  = GND
  DQ7_A  = M_F_CPU1_SA_DQ<7>
  VSS69  = GND
  DQ10_A  = M_F_CPU1_SA_DQ<10>
  VSS70  = GND
  DQ11_A  = M_F_CPU1_SA_DQ<11>
  VSS71  = GND
  \dqs6_a_c||tdqs6_a_c||dqs6_a_t||tdqs6_a_t\  = M_F_CPU1_SA_DQS_DN<6>
  \dqs6_a_t||tdqs6_a_t\  = M_F_CPU1_SA_DQS_DP<6>
  VSS72  = GND
  DQ14_A  = M_F_CPU1_SA_DQ<14>
  VSS73  = GND
  DQ15_A  = M_F_CPU1_SA_DQ<15>
  VSS74  = GND
  DQ18_A  = M_F_CPU1_SA_DQ<18>
  VSS75  = GND
  DQ19_A  = M_F_CPU1_SA_DQ<19>
  VSS76  = GND
  \dqs7_a_c||tdqs7_a_c\  = M_F_CPU1_SA_DQS_DN<7>
  \dqs7_a_t||tdqs7_a_t\  = M_F_CPU1_SA_DQS_DP<7>
  VSS77  = GND
  DQ22_A  = M_F_CPU1_SA_DQ<22>
  VSS78  = GND
  DQ23_A  = M_F_CPU1_SA_DQ<23>
  VSS79  = GND
  DQ26_A  = M_F_CPU1_SA_DQ<26>
  VSS80  = GND
  DQ27_A  = M_F_CPU1_SA_DQ<27>
  VSS81  = GND
  \dqs8_a_c||tdqs8_a_c\  = M_F_CPU1_SA_DQS_DN<8>
  \dqs8_a_t||tdqs8_a_t\  = M_F_CPU1_SA_DQS_DP<8>
  VSS82  = GND
  DQ30_A  = M_F_CPU1_SA_DQ<30>
  VSS83  = GND
  DQ31_A  = M_F_CPU1_SA_DQ<31>
  VSS84  = GND
  CB2_A  = M_F_CPU1_SA_CB<2>
  VSS85  = GND
  CB3_A  = M_F_CPU1_SA_CB<3>
  VSS86  = GND
  \dqs9_a_c||tdqs9_a_c\  = M_F_CPU1_SA_DQS_DN<9>
  \dqs9_a_t||tdqs9_a_t\  = M_F_CPU1_SA_DQS_DP<9>
  VSS87  = GND
  CB6_A  = M_F_CPU1_SA_CB<6>
  VSS88  = GND
  CB7_A  = M_F_CPU1_SA_CB<7>
  VSS89  = GND
  RESET_N  = RST_M_EF_CPU1_FPGA_N
  VSS90  = GND
  CS1_A_N  = M_F_CPU1_SA_CS_N<1>
  VSS91  = GND
  CA1_A  = M_F_CPU1_SA_CA<1>
  VSS92  = GND
  CA3_A  = M_F_CPU1_SA_CA<3>
  VSS93  = GND
  CA5_A  = M_F_CPU1_SA_CA<5>
  VSS94  = GND
  CK_T  = M_F_CPU1_CLK_DP<0>
  CK_C  = M_F_CPU1_CLK_DN<0>
  VSS95  = GND
  RFU4  = TP_CHF_CPU1_DIMM1_FRU_4
  CA1_B  = M_F_CPU1_SB_CA<1>
  VSS96  = GND
  CA3_B  = M_F_CPU1_SB_CA<3>
  VSS97  = GND
  CA5_B  = M_F_CPU1_SB_CA<5>
  VSS98  = GND
  PAR_B  = M_F_CPU1_SB_PAR
  VSS99  = GND
  CS1_B_N  = M_F_CPU1_SB_CS_N<1>
  VSS100  = GND
  RFU5  = TP_CHF_CPU1_DIMM1_FRU_5
  RFU6  = TP_CHF_CPU1_DIMM1_FRU_6
  VSS101  = GND
  CB6_B  = M_F_CPU1_SB_CB<6>
  VSS102  = GND
  CB7_B  = M_F_CPU1_SB_CB<7>
  VSS103  = GND
  DQS4_B_C  = M_F_CPU1_SB_DQS_DN<4>
  DQS4_B_T  = M_F_CPU1_SB_DQS_DP<4>
  VSS104  = GND
  CB2_B  = M_F_CPU1_SB_CB<2>
  VSS105  = GND
  CB3_B  = M_F_CPU1_SB_CB<3>
  VSS106  = GND
  DQ2_B  = M_F_CPU1_SB_DQ<2>
  VSS107  = GND
  DQ3_B  = M_F_CPU1_SB_DQ<3>
  VSS108  = GND
  \dqs5_b_c||tdqs5_b_c\  = M_F_CPU1_SB_DQS_DN<5>
  \dqs5_b_t||tdqs5_b_t\  = M_F_CPU1_SB_DQS_DP<5>
  VSS109  = GND
  DQ6_B  = M_F_CPU1_SB_DQ<6>
  VSS110  = GND
  DQ7_B  = M_F_CPU1_SB_DQ<7>
  VSS111  = GND
  DQ10_B  = M_F_CPU1_SB_DQ<10>
  VSS112  = GND
  DQ11_B  = M_F_CPU1_SB_DQ<11>
  VSS113  = GND
  \dqs6_b_c||tdqs6_b_c\  = M_F_CPU1_SB_DQS_DN<6>
  \dqs6_b_t||tdqs6_b_t\  = M_F_CPU1_SB_DQS_DP<6>
  VSS114  = GND
  DQ14_B  = M_F_CPU1_SB_DQ<14>
  VSS115  = GND
  DQ15_B  = M_F_CPU1_SB_DQ<15>
  VSS116  = GND
  DQ18_B  = M_F_CPU1_SB_DQ<18>
  VSS117  = GND
  DQ19_B  = M_F_CPU1_SB_DQ<19>
  VSS118  = GND
  \dqs7_b_c||tdqs7_b_c\  = M_F_CPU1_SB_DQS_DN<7>
  \dqs7_b_t||tdqs7_b_t\  = M_F_CPU1_SB_DQS_DP<7>
  VSS119  = GND
  DQ22_B  = M_F_CPU1_SB_DQ<22>
  VSS120  = GND
  DQ23_B  = M_F_CPU1_SB_DQ<23>
  VSS121  = GND
  DQ26_B  = M_F_CPU1_SB_DQ<26>
  VSS122  = GND
  DQ27_B  = M_F_CPU1_SB_DQ<27>
  VSS123  = GND
  \dqs8_b_c||tdqs8_b_c\  = M_F_CPU1_SB_DQS_DN<8>
  \dqs8_b_t||tdqs8_b_t\  = M_F_CPU1_SB_DQS_DP<8>
  VSS124  = GND
  DQ30_B  = M_F_CPU1_SB_DQ<30>
  VSS125  = GND
  DQ31_B  = M_F_CPU1_SB_DQ<31>
  VSS126  = GND
  G1  = GND
  G2  = GND
  G3  = GND

(kicad_pcb
	(version 20260206)
	(generator "pcbnew")
	(generator_version "10.0")
	(general
		(thickness 1.6)
		(legacy_teardrops no)
	)
	(paper "A4")
	(title_block
		(title "03242023_DA0F0TMBIJ0_F0T_Motherboard_J_brd_V01_OCP.brd")
		(comment 1 "Grand Teton / footprint 1301 of 6105 (J27), pads 1-45 of 291")
	)
	(layers
		(0 "F.Cu" signal "TOP")
		(4 "In1.Cu" signal "GND")
		(6 "In2.Cu" signal "IN1")
		(8 "In3.Cu" signal "GND1")
		(10 "In4.Cu" signal "IN2")
		(12 "In5.Cu" signal "GND2")
		(14 "In6.Cu" signal "IN3")
		(16 "In7.Cu" signal "GND3")
		(18 "In8.Cu" signal "VCC")
		(20 "In9.Cu" signal "VCC1")
		(22 "In10.Cu" signal "GND4")
		(24 "In11.Cu" signal "IN4")
		(26 "In12.Cu" signal "GND5")
		(28 "In13.Cu" signal "IN5")
		(30 "In14.Cu" signal "GND6")
		(32 "In15.Cu" signal "IN6")
		(34 "In16.Cu" signal "GND7")
		(2 "B.Cu" signal "BOTTOM")
		(9 "F.Adhes" user "F.Adhesive")
		(11 "B.Adhes" user "B.Adhesive")
		(13 "F.Paste" user "Package Geometry/Pastemask Top")
		(15 "B.Paste" user "Package Geometry/Pastemask Bottom")
		(5 "F.SilkS" user "Ref Des/Silkscreen Top")
		(7 "B.SilkS" user "Ref Des/Silkscreen Bottom")
		(1 "F.Mask" user "Board Geometry/Soldermask Top")
		(3 "B.Mask" user "Board Geometry/Soldermask Bottom")
		(17 "Dwgs.User" user "User.Drawings")
		(19 "Cmts.User" user "User.Comments")
		(21 "Eco1.User" user "User.Eco1")
		(23 "Eco2.User" user "User.Eco2")
		(25 "Edge.Cuts" user "Board Geometry/Outline")
		(27 "Margin" user)
		(31 "F.CrtYd" user "Package Geometry/Place Bound Top")
		(29 "B.CrtYd" user "Package Geometry/Place Bound Bottom")
		(35 "F.Fab" user "Ref Des/Assembly Top")
		(33 "B.Fab" user "Ref Des/Assembly Bottom")
	)
	(footprint ""
		(layer "F.Cu")
		(at 183.49468 -258.091686)
		(property "Reference" "J27"
			(at 2.19456 -81.755488 0)
			(unlocked yes)
			(layer "F.SilkS")
			(effects
				(font
					(size 0.7874 0.5842)
					(thickness 0.1524)
				)
				(justify left)
			)
		)
		(property "Value" ""
			(at 0 0 0)
			(layer "F.Fab")
			(effects
				(font
					(size 1.27 1.27)
				)
			)
		)
		(duplicate_pad_numbers_are_jumpers no)
		(pad "1" smd rect
			(at -2.050034 -63.324994 270)
			(size 0.519938 1.4986)
			(layers "F.Cu" "F.Mask" "F.Paste")
			(net "P12V_S3_AUX_CPU1_NVDIMM")
		)
		(pad "2" smd rect
			(at -2.050034 -62.47511 270)
			(size 0.519938 1.4986)
			(layers "F.Cu" "F.Mask" "F.Paste")
			(net "TP_CHF_CPU1_DIMM1_FRU_0")
		)
		(pad "3" smd rect
			(at -2.050034 -61.624972 270)
			(size 0.519938 1.4986)
			(layers "F.Cu" "F.Mask" "F.Paste")
			(net "P3V3_AUX")
		)
		(pad "4" smd rect
			(at -2.050034 -60.775088 270)
			(size 0.519938 1.4986)
			(layers "F.Cu" "F.Mask" "F.Paste")
			(net "I3C_SPD_DDREFGH_CPU1_LVC1_SCL_2")
		)
		(pad "5" smd rect
			(at -2.050034 -59.92495 270)
			(size 0.519938 1.4986)
			(layers "F.Cu" "F.Mask" "F.Paste")
			(net "I3C_SPD_DDREFGH_CPU1_LVC1_SDA")
		)
		(pad "6" smd rect
			(at -2.050034 -59.075066 270)
			(size 0.519938 1.4986)
			(layers "F.Cu" "F.Mask" "F.Paste")
			(net "GND")
		)
		(pad "7" smd rect
			(at -2.050034 -58.224928 270)
			(size 0.519938 1.4986)
			(layers "F.Cu" "F.Mask" "F.Paste")
			(net "M_F_CPU1_SA_DQ<0>")
		)
		(pad "8" smd rect
			(at -2.050034 -57.375044 270)
			(size 0.519938 1.4986)
			(layers "F.Cu" "F.Mask" "F.Paste")
			(net "GND")
		)
		(pad "9" smd rect
			(at -2.050034 -56.524906 270)
			(size 0.519938 1.4986)
			(layers "F.Cu" "F.Mask" "F.Paste")
			(net "M_F_CPU1_SA_DQ<1>")
		)
		(pad "10" smd rect
			(at -2.050034 -55.675022 270)
			(size 0.519938 1.4986)
			(layers "F.Cu" "F.Mask" "F.Paste")
			(net "GND")
		)
		(pad "11" smd rect
			(at -2.050034 -54.824884 270)
			(size 0.519938 1.4986)
			(layers "F.Cu" "F.Mask" "F.Paste")
			(net "M_F_CPU1_SA_DQS_DP<0>")
		)
		(pad "12" smd rect
			(at -2.050034 -53.975 270)
			(size 0.519938 1.4986)
			(layers "F.Cu" "F.Mask" "F.Paste")
			(net "M_F_CPU1_SA_DQS_DN<0>")
		)
		(pad "13" smd rect
			(at -2.050034 -53.125116 270)
			(size 0.519938 1.4986)
			(layers "F.Cu" "F.Mask" "F.Paste")
			(net "GND")
		)
		(pad "14" smd rect
			(at -2.050034 -52.274978 270)
			(size 0.519938 1.4986)
			(layers "F.Cu" "F.Mask" "F.Paste")
			(net "M_F_CPU1_SA_DQ<4>")
		)
		(pad "15" smd rect
			(at -2.050034 -51.425094 270)
			(size 0.519938 1.4986)
			(layers "F.Cu" "F.Mask" "F.Paste")
			(net "GND")
		)
		(pad "16" smd rect
			(at -2.050034 -50.574956 270)
			(size 0.519938 1.4986)
			(layers "F.Cu" "F.Mask" "F.Paste")
			(net "M_F_CPU1_SA_DQ<5>")
		)
		(pad "17" smd rect
			(at -2.050034 -49.725072 270)
			(size 0.519938 1.4986)
			(layers "F.Cu" "F.Mask" "F.Paste")
			(net "GND")
		)
		(pad "18" smd rect
			(at -2.050034 -48.874934 270)
			(size 0.519938 1.4986)
			(layers "F.Cu" "F.Mask" "F.Paste")
			(net "M_F_CPU1_SA_DQ<8>")
		)
		(pad "19" smd rect
			(at -2.050034 -48.02505 270)
			(size 0.519938 1.4986)
			(layers "F.Cu" "F.Mask" "F.Paste")
			(net "GND")
		)
		(pad "20" smd rect
			(at -2.050034 -47.174912 270)
			(size 0.519938 1.4986)
			(layers "F.Cu" "F.Mask" "F.Paste")
			(net "M_F_CPU1_SA_DQ<9>")
		)
		(pad "21" smd rect
			(at -2.050034 -46.325028 270)
			(size 0.519938 1.4986)
			(layers "F.Cu" "F.Mask" "F.Paste")
			(net "GND")
		)
		(pad "22" smd rect
			(at -2.050034 -45.47489 270)
			(size 0.519938 1.4986)
			(layers "F.Cu" "F.Mask" "F.Paste")
			(net "M_F_CPU1_SA_DQS_DP<1>")
		)
		(pad "23" smd rect
			(at -2.050034 -44.625006 270)
			(size 0.519938 1.4986)
			(layers "F.Cu" "F.Mask" "F.Paste")
			(net "M_F_CPU1_SA_DQS_DN<1>")
		)
		(pad "24" smd rect
			(at -2.050034 -43.775122 270)
			(size 0.519938 1.4986)
			(layers "F.Cu" "F.Mask" "F.Paste")
			(net "GND")
		)
		(pad "25" smd rect
			(at -2.050034 -42.924984 270)
			(size 0.519938 1.4986)
			(layers "F.Cu" "F.Mask" "F.Paste")
			(net "M_F_CPU1_SA_DQ<12>")
		)
		(pad "26" smd rect
			(at -2.050034 -42.0751 270)
			(size 0.519938 1.4986)
			(layers "F.Cu" "F.Mask" "F.Paste")
			(net "GND")
		)
		(pad "27" smd rect
			(at -2.050034 -41.224962 270)
			(size 0.519938 1.4986)
			(layers "F.Cu" "F.Mask" "F.Paste")
			(net "M_F_CPU1_SA_DQ<13>")
		)
		(pad "28" smd rect
			(at -2.050034 -40.375078 270)
			(size 0.519938 1.4986)
			(layers "F.Cu" "F.Mask" "F.Paste")
			(net "GND")
		)
		(pad "29" smd rect
			(at -2.050034 -39.52494 270)
			(size 0.519938 1.4986)
			(layers "F.Cu" "F.Mask" "F.Paste")
			(net "M_F_CPU1_SA_DQ<16>")
		)
		(pad "30" smd rect
			(at -2.050034 -38.675056 270)
			(size 0.519938 1.4986)
			(layers "F.Cu" "F.Mask" "F.Paste")
			(net "GND")
		)
		(pad "31" smd rect
			(at -2.050034 -37.824918 270)
			(size 0.519938 1.4986)
			(layers "F.Cu" "F.Mask" "F.Paste")
			(net "M_F_CPU1_SA_DQ<17>")
		)
		(pad "32" smd rect
			(at -2.050034 -36.975034 270)
			(size 0.519938 1.4986)
			(layers "F.Cu" "F.Mask" "F.Paste")
			(net "GND")
		)
		(pad "33" smd rect
			(at -2.050034 -36.124896 270)
			(size 0.519938 1.4986)
			(layers "F.Cu" "F.Mask" "F.Paste")
			(net "M_F_CPU1_SA_DQS_DP<2>")
		)
		(pad "34" smd rect
			(at -2.050034 -35.275012 270)
			(size 0.519938 1.4986)
			(layers "F.Cu" "F.Mask" "F.Paste")
			(net "M_F_CPU1_SA_DQS_DN<2>")
		)
		(pad "35" smd rect
			(at -2.050034 -34.425128 270)
			(size 0.519938 1.4986)
			(layers "F.Cu" "F.Mask" "F.Paste")
			(net "GND")
		)
		(pad "36" smd rect
			(at -2.050034 -33.57499 270)
			(size 0.519938 1.4986)
			(layers "F.Cu" "F.Mask" "F.Paste")
			(net "M_F_CPU1_SA_DQ<20>")
		)
		(pad "37" smd rect
			(at -2.050034 -32.725106 270)
			(size 0.519938 1.4986)
			(layers "F.Cu" "F.Mask" "F.Paste")
			(net "GND")
		)
		(pad "38" smd rect
			(at -2.050034 -31.874968 270)
			(size 0.519938 1.4986)
			(layers "F.Cu" "F.Mask" "F.Paste")
			(net "M_F_CPU1_SA_DQ<21>")
		)
		(pad "39" smd rect
			(at -2.050034 -31.025084 270)
			(size 0.519938 1.4986)
			(layers "F.Cu" "F.Mask" "F.Paste")
			(net "GND")
		)
		(pad "40" smd rect
			(at -2.050034 -30.174946 270)
			(size 0.519938 1.4986)
			(layers "F.Cu" "F.Mask" "F.Paste")
			(net "M_F_CPU1_SA_DQ<24>")
		)
		(pad "41" smd rect
			(at -2.050034 -29.325062 270)
			(size 0.519938 1.4986)
			(layers "F.Cu" "F.Mask" "F.Paste")
			(net "GND")
		)
		(pad "42" smd rect
			(at -2.050034 -28.474924 270)
			(size 0.519938 1.4986)
			(layers "F.Cu" "F.Mask" "F.Paste")
			(net "M_F_CPU1_SA_DQ<25>")
		)
		(pad "43" smd rect
			(at -2.050034 -27.62504 270)
			(size 0.519938 1.4986)
			(layers "F.Cu" "F.Mask" "F.Paste")
			(net "GND")
		)
		(pad "44" smd rect
			(at -2.050034 -26.774902 270)
			(size 0.519938 1.4986)
			(layers "F.Cu" "F.Mask" "F.Paste")
			(net "M_F_CPU1_SA_DQS_DP<3>")
		)
		(pad "45" smd rect
			(at -2.050034 -25.925018 270)
			(size 0.519938 1.4986)
			(layers "F.Cu" "F.Mask" "F.Paste")
			(net "M_F_CPU1_SA_DQS_DN<3>")
		)
	)
)
